# T6G (Grand Teton) — schematic netlist excerpt (pin names and nets, part order shuffled) for the footprints in the layout excerpt that follows; sources: Cadence DE-HDL packaged netlist, KiCad conversion of 04192023_DAF0TMB3IC0_F0TG_MB_C_brd_V02_OCP.brd

U32  MOSFET_N  BSS138K IC  pkg SMLF  page 142
  DRAIN  = HP_LVC3_OCP_V3_2_PRSNT2
  GATE  = HP_LVC3_OCP_V3_2_PRSNT2_N
  SOURCE  = GND

C7040  Q_CAP  47UF 4V 20% X6S  pkg C0805  page 345 : A = P0V9_CPU1_RT_2D ; B = GND
PL8045  Q_INDUCTOR  100NH/16A IND  pkg SMLF  page 190 : \1\ = P12V_AUX ; \2\ = SW_P3V3_AUX_FLT

(kicad_pcb
	(version 20260206)
	(generator "pcbnew")
	(generator_version "10.0")
	(general
		(thickness 1.6)
		(legacy_teardrops no)
	)
	(paper "A4")
	(title_block
		(title "04192023_DAF0TMB3IC0_F0TG_MB_C_brd_V02_OCP.brd")
		(comment 1 "Grand Teton / footprints 3761-3763 of 8354")
	)
	(layers
		(0 "F.Cu" signal "TOP")
		(4 "In1.Cu" signal "GND")
		(6 "In2.Cu" signal "IN1")
		(8 "In3.Cu" signal "GND1")
		(10 "In4.Cu" signal "IN2")
		(12 "In5.Cu" signal "GND2")
		(14 "In6.Cu" signal "IN3")
		(16 "In7.Cu" signal "GND3")
		(18 "In8.Cu" signal "VCC")
		(20 "In9.Cu" signal "VCC1")
		(22 "In10.Cu" signal "GND4")
		(24 "In11.Cu" signal "IN4")
		(26 "In12.Cu" signal "GND5")
		(28 "In13.Cu" signal "IN5")
		(30 "In14.Cu" signal "GND6")
		(32 "In15.Cu" signal "IN6")
		(34 "In16.Cu" signal "GND7")
		(2 "B.Cu" signal "BOTTOM")
		(9 "F.Adhes" user "F.Adhesive")
		(11 "B.Adhes" user "B.Adhesive")
		(13 "F.Paste" user "Package Geometry/Pastemask Top")
		(15 "B.Paste" user "Package Geometry/Pastemask Bottom")
		(5 "F.SilkS" user "Ref Des/Silkscreen Top")
		(7 "B.SilkS" user "Ref Des/Silkscreen Bottom")
		(1 "F.Mask" user "Board Geometry/Soldermask Top")
		(3 "B.Mask" user "Board Geometry/Soldermask Bottom")
		(17 "Dwgs.User" user "User.Drawings")
		(19 "Cmts.User" user "User.Comments")
		(21 "Eco1.User" user "User.Eco1")
		(23 "Eco2.User" user "User.Eco2")
		(25 "Edge.Cuts" user "Board Geometry/Outline")
		(27 "Margin" user)
		(31 "F.CrtYd" user "Package Geometry/Place Bound Top")
		(29 "B.CrtYd" user "Package Geometry/Place Bound Bottom")
		(35 "F.Fab" user "Ref Des/Assembly Top")
		(33 "B.Fab" user "Ref Des/Assembly Bottom")
	)
	(footprint ""
		(layer "F.Cu")
		(at 435.80812 -45.025056 90)
		(property "Reference" "PL8045"
			(at -1.629156 -3.891026 90)
			(unlocked yes)
			(layer "F.SilkS")
			(effects
				(font
					(size 0.7874 0.5842)
					(thickness 0.1524)
				)
				(justify left)
			)
		)
		(property "Value" ""
			(at 0 0 90)
			(layer "F.Fab")
			(effects
				(font
					(size 1.27 1.27)
				)
			)
		)
		(duplicate_pad_numbers_are_jumpers no)
		(fp_line
			(start 2.249932 -2.249932)
			(end 2.249932 -1.3843)
			(stroke
				(width 0.1524)
				(type default)
			)
			(layer "F.SilkS")
		)
		(fp_line
			(start -2.249932 -2.249932)
			(end 2.249932 -2.249932)
			(stroke
				(width 0.1524)
				(type default)
			)
			(layer "F.SilkS")
		)
		(fp_line
			(start -2.249932 -1.3843)
			(end -2.249932 -2.249932)
			(stroke
				(width 0.1524)
				(type default)
			)
			(layer "F.SilkS")
		)
		(fp_line
			(start 2.249932 1.3843)
			(end 2.249932 2.249932)
			(stroke
				(width 0.1524)
				(type default)
			)
			(layer "F.SilkS")
		)
		(fp_line
			(start 2.249932 2.249932)
			(end -2.249932 2.249932)
			(stroke
				(width 0.1524)
				(type default)
			)
			(layer "F.SilkS")
		)
		(fp_line
			(start -2.249932 2.249932)
			(end -2.249932 1.3843)
			(stroke
				(width 0.1524)
				(type default)
			)
			(layer "F.SilkS")
		)
		(fp_line
			(start 2.249932 -2.249932)
			(end 2.249932 2.249932)
			(stroke
				(width 0.1)
				(type default)
			)
			(layer "F.Fab")
		)
		(fp_line
			(start -2.249932 -2.249932)
			(end 2.249932 -2.249932)
			(stroke
				(width 0.1)
				(type default)
			)
			(layer "F.Fab")
		)
		(fp_line
			(start 2.249932 2.249932)
			(end -2.249932 2.249932)
			(stroke
				(width 0.1)
				(type default)
			)
			(layer "F.Fab")
		)
		(fp_line
			(start -2.249932 2.249932)
			(end -2.249932 -2.249932)
			(stroke
				(width 0.1)
				(type default)
			)
			(layer "F.Fab")
		)
		(pad "1" smd rect
			(at -1.82499 0 90)
			(size 1.0668 2.5146)
			(layers "F.Cu" "F.Mask" "F.Paste")
			(net "P12V_AUX")
		)
		(pad "2" smd rect
			(at 1.82499 0 90)
			(size 1.0668 2.5146)
			(layers "F.Cu" "F.Mask" "F.Paste")
			(net "SW_P3V3_AUX_FLT")
		)
	)
	(footprint ""
		(layer "F.Cu")
		(at 142.074392 -401.884896 90)
		(property "Reference" "C7040"
			(at 0 0 90)
			(layer "F.SilkS")
			(hide yes)
			(effects
				(font
					(size 1.27 1.27)
				)
			)
		)
		(property "Value" ""
			(at 0 0 90)
			(layer "F.Fab")
			(effects
				(font
					(size 1.27 1.27)
				)
			)
		)
		(duplicate_pad_numbers_are_jumpers no)
		(fp_line
			(start 1.524 -0.762)
			(end 1.524 0.762)
			(stroke
				(width 0.1524)
				(type default)
			)
			(layer "F.SilkS")
		)
		(fp_line
			(start -1.524 -0.762)
			(end 1.524 -0.762)
			(stroke
				(width 0.1524)
				(type default)
			)
			(layer "F.SilkS")
		)
		(fp_line
			(start 1.524 0.762)
			(end -1.524 0.762)
			(stroke
				(width 0.1524)
				(type default)
			)
			(layer "F.SilkS")
		)
		(fp_line
			(start -1.524 0.762)
			(end -1.524 -0.762)
			(stroke
				(width 0.1524)
				(type default)
			)
			(layer "F.SilkS")
		)
		(fp_line
			(start 1.1049 -0.724916)
			(end -1.1049 -0.724916)
			(stroke
				(width 0.1)
				(type default)
			)
			(layer "F.Fab")
		)
		(fp_line
			(start -1.1049 -0.724916)
			(end -1.1049 0.724916)
			(stroke
				(width 0.1)
				(type default)
			)
			(layer "F.Fab")
		)
		(fp_line
			(start 1.1049 0.724916)
			(end 1.1049 -0.724916)
			(stroke
				(width 0.1)
				(type default)
			)
			(layer "F.Fab")
		)
		(fp_line
			(start -1.1049 0.724916)
			(end 1.1049 0.724916)
			(stroke
				(width 0.1)
				(type default)
			)
			(layer "F.Fab")
		)
		(pad "1" smd rect
			(at -0.889 0 270)
			(size 1.016 1.27)
			(layers "F.Cu" "F.Mask" "F.Paste")
			(net "P0V9_CPU1_RT_2D")
		)
		(pad "2" smd rect
			(at 0.889 0 270)
			(size 1.016 1.27)
			(layers "F.Cu" "F.Mask" "F.Paste")
			(net "GND")
		)
	)
	(footprint ""
		(layer "F.Cu")
		(at 46.355 -38.354)
		(property "Reference" "U32"
			(at -2.017776 -2.360422 0)
			(unlocked yes)
			(layer "F.SilkS")
			(effects
				(font
					(size 0.7874 0.5842)
					(thickness 0.1524)
				)
			)
		)
		(property "Value" ""
			(at 0 0 0)
			(layer "F.Fab")
			(effects
				(font
					(size 1.27 1.27)
				)
			)
		)
		(duplicate_pad_numbers_are_jumpers no)
		(fp_line
			(start -1.949958 -1.610106)
			(end 1.949958 -1.610106)
			(stroke
				(width 0.1524)
				(type default)
			)
			(layer "F.SilkS")
		)
		(fp_line
			(start -1.949958 1.610106)
			(end -1.949958 -1.610106)
			(stroke
				(width 0.1524)
				(type default)
			)
			(layer "F.SilkS")
		)
		(fp_line
			(start 1.949958 -1.560068)
			(end 1.949958 1.610106)
			(stroke
				(width 0.1524)
				(type default)
			)
			(layer "F.SilkS")
		)
		(fp_line
			(start 1.949958 1.610106)
			(end -1.949958 1.610106)
			(stroke
				(width 0.1524)
				(type default)
			)
			(layer "F.SilkS")
		)
		(fp_line
			(start -0.750062 -1.560068)
			(end 0.750062 -1.560068)
			(stroke
				(width 0.1)
				(type default)
			)
			(layer "F.Fab")
		)
		(fp_line
			(start -0.750062 1.560068)
			(end -0.750062 -1.560068)
			(stroke
				(width 0.1)
				(type default)
			)
			(layer "F.Fab")
		)
		(fp_line
			(start 0.750062 -1.560068)
			(end 0.750062 1.560068)
			(stroke
				(width 0.1)
				(type default)
			)
			(layer "F.Fab")
		)
		(fp_line
			(start 0.750062 1.560068)
			(end -0.750062 1.560068)
			(stroke
				(width 0.1)
				(type default)
			)
			(layer "F.Fab")
		)
		(pad "D" smd rect
			(at 1.100074 0 270)
			(size 1.016 1.4224)
			(layers "F.Cu" "F.Mask" "F.Paste")
			(net "HP_LVC3_OCP_V3_2_PRSNT2")
		)
		(pad "G" smd rect
			(at -1.100074 -0.94996 270)
			(size 1.016 1.4224)
			(layers "F.Cu" "F.Mask" "F.Paste")
			(net "HP_LVC3_OCP_V3_2_PRSNT2_N")
		)
		(pad "S" smd rect
			(at -1.100074 0.94996 270)
			(size 1.016 1.4224)
			(layers "F.Cu" "F.Mask" "F.Paste")
			(net "GND")
		)
	)
)
